(kicad_pcb
	(version 20260206)
	(generator "pcbnew")
	(generator_version "10.0")
	(general
		(thickness 1.6)
		(legacy_teardrops no)
	)
	(paper "A4")
	(title_block
		(title "Wiwynn_Tioga_Pass_MB.brd")
		(comment 1 "Tioga Pass / footprints 2638-2645 of 4770")
	)
	(layers
		(0 "F.Cu" signal "TOP")
		(4 "In1.Cu" signal "L2GND")
		(6 "In2.Cu" signal "L3")
		(8 "In3.Cu" signal "L4GND")
		(10 "In4.Cu" signal "L5")
		(12 "In5.Cu" signal "L6GND")
		(14 "In6.Cu" signal "L7VCC")
		(16 "In7.Cu" signal "L8VCC")
		(18 "In8.Cu" signal "L9GND")
		(20 "In9.Cu" signal "L10")
		(22 "In10.Cu" signal "L11GND")
		(24 "In11.Cu" signal "L12")
		(26 "In12.Cu" signal "L13GND")
		(2 "B.Cu" signal "BOTTOM")
		(9 "F.Adhes" user "F.Adhesive")
		(11 "B.Adhes" user "B.Adhesive")
		(13 "F.Paste" user "Package Geometry/Pastemask Top")
		(15 "B.Paste" user "Package Geometry/Pastemask Bottom")
		(5 "F.SilkS" user "Ref Des/Silkscreen Top")
		(7 "B.SilkS" user "Ref Des/Silkscreen Bottom")
		(1 "F.Mask" user "Board Geometry/Soldermask Top")
		(3 "B.Mask" user "Board Geometry/Soldermask Bottom")
		(17 "Dwgs.User" user "User.Drawings")
		(19 "Cmts.User" user "User.Comments")
		(21 "Eco1.User" user "User.Eco1")
		(23 "Eco2.User" user "User.Eco2")
		(25 "Edge.Cuts" user "Board Geometry/Outline")
		(27 "Margin" user)
		(31 "F.CrtYd" user "Package Geometry/Place Bound Top")
		(29 "B.CrtYd" user "Package Geometry/Place Bound Bottom")
		(35 "F.Fab" user "Ref Des/Assembly Top")
		(33 "B.Fab" user "Ref Des/Assembly Bottom")
	)
	(footprint ""
		(layer "B.Cu")
		(at 457.533756 -21.494242 90)
		(property "Reference" "C9W6"
			(at 0.8382 -0.67818 90)
			(unlocked yes)
			(layer "B.SilkS")
			(effects
				(font
					(size 0.4064 0.254)
					(thickness 0.1524)
				)
				(justify left mirror)
			)
		)
		(property "Value" ""
			(at 0 0 90)
			(layer "B.Fab")
			(effects
				(font
					(size 1.27 1.27)
				)
				(justify mirror)
			)
		)
		(duplicate_pad_numbers_are_jumpers no)
		(fp_poly
			(pts
				(xy -0.3048 -0.1016) (xy -0.3048 0.9906) (xy 0.3048 0.9906) (xy 0.3048 -0.1016)
			)
			(stroke
				(width 0)
				(type default)
			)
			(fill no)
			(layer "B.CrtYd")
		)
		(fp_line
			(start 0.3048 -0.1016)
			(end 0.3048 0.9906)
			(stroke
				(width 0.1)
				(type default)
			)
			(layer "B.Fab")
		)
		(fp_line
			(start -0.3048 -0.1016)
			(end 0.3048 -0.1016)
			(stroke
				(width 0.1)
				(type default)
			)
			(layer "B.Fab")
		)
		(fp_line
			(start 0.3048 0.9906)
			(end -0.3048 0.9906)
			(stroke
				(width 0.1)
				(type default)
			)
			(layer "B.Fab")
		)
		(fp_line
			(start -0.3048 0.9906)
			(end -0.3048 -0.1016)
			(stroke
				(width 0.1)
				(type default)
			)
			(layer "B.Fab")
		)
		(pad "1" smd rect
			(at 0 0 270)
			(size 0.508 0.508)
			(layers "B.Cu" "B.Mask" "B.Paste")
			(net "PWRGD_P3V3_STBY")
		)
		(pad "2" smd rect
			(at 0 0.889 270)
			(size 0.508 0.508)
			(layers "B.Cu" "B.Mask" "B.Paste")
			(net "GND")
		)
		(zone
			(layer "B.Cu")
			(hatch none 0.5)
			(connect_pads
				(clearance 0)
			)
			(min_thickness 0.25)
			(keepout
				(tracks allowed)
				(vias not_allowed)
				(pads allowed)
				(copperpour not_allowed)
				(footprints allowed)
			)
			(placement
				(enabled no)
				(sheetname "")
			)
			(fill
				(thermal_gap 0.5)
				(thermal_bridge_width 0.5)
				(island_removal_mode 0)
			)
			(polygon
				(pts
					(xy 457.787756 -21.748242) (xy 457.787756 -21.240242) (xy 458.168756 -21.240242) (xy 458.168756 -21.748242)
				)
			)
		)
		(zone
			(layer "B.Cu")
			(hatch none 0.5)
			(connect_pads
				(clearance 0)
			)
			(min_thickness 0.25)
			(keepout
				(tracks not_allowed)
				(vias allowed)
				(pads allowed)
				(copperpour not_allowed)
				(footprints allowed)
			)
			(placement
				(enabled no)
				(sheetname "")
			)
			(fill
				(thermal_gap 0.5)
				(thermal_bridge_width 0.5)
				(island_removal_mode 0)
			)
			(polygon
				(pts
					(xy 458.168756 -21.748242) (xy 458.168756 -21.240242) (xy 457.787756 -21.240242) (xy 457.787756 -21.748242)
				)
			)
		)
	)
	(footprint ""
		(layer "B.Cu")
		(at 63.2968 -88.8492 90)
		(property "Reference" "R8N5"
			(at 0 0 90)
			(layer "B.SilkS")
			(hide yes)
			(effects
				(font
					(size 1.27 1.27)
				)
				(justify mirror)
			)
		)
		(property "Value" ""
			(at 0 0 90)
			(layer "B.Fab")
			(effects
				(font
					(size 1.27 1.27)
				)
				(justify mirror)
			)
		)
		(duplicate_pad_numbers_are_jumpers no)
		(fp_poly
			(pts
				(xy 0.2794 -0.1016) (xy -0.2794 -0.1016) (xy -0.2794 0.9906) (xy 0.2794 0.9906)
			)
			(stroke
				(width 0)
				(type default)
			)
			(fill no)
			(layer "B.CrtYd")
		)
		(fp_line
			(start 0.2794 -0.1016)
			(end 0.2794 0.9906)
			(stroke
				(width 0.1)
				(type default)
			)
			(layer "B.Fab")
		)
		(fp_line
			(start -0.2794 -0.1016)
			(end 0.2794 -0.1016)
			(stroke
				(width 0.1)
				(type default)
			)
			(layer "B.Fab")
		)
		(fp_line
			(start 0.2794 0.9906)
			(end -0.2794 0.9906)
			(stroke
				(width 0.1)
				(type default)
			)
			(layer "B.Fab")
		)
		(fp_line
			(start -0.2794 0.9906)
			(end -0.2794 -0.1016)
			(stroke
				(width 0.1)
				(type default)
			)
			(layer "B.Fab")
		)
		(pad "1" smd rect
			(at 0 0 270)
			(size 0.508 0.508)
			(layers "B.Cu" "B.Mask" "B.Paste")
			(net "P3V3_STBY")
		)
		(pad "2" smd rect
			(at 0 0.889 270)
			(size 0.508 0.508)
			(layers "B.Cu" "B.Mask" "B.Paste")
			(net "FM_CPU1_PKGID1")
		)
		(zone
			(layer "B.Cu")
			(hatch none 0.5)
			(connect_pads
				(clearance 0)
			)
			(min_thickness 0.25)
			(keepout
				(tracks allowed)
				(vias not_allowed)
				(pads allowed)
				(copperpour not_allowed)
				(footprints allowed)
			)
			(placement
				(enabled no)
				(sheetname "")
			)
			(fill
				(thermal_gap 0.5)
				(thermal_bridge_width 0.5)
				(island_removal_mode 0)
			)
			(polygon
				(pts
					(xy 63.5508 -89.1032) (xy 63.5508 -88.5952) (xy 63.9318 -88.5952) (xy 63.9318 -89.1032)
				)
			)
		)
		(zone
			(layer "B.Cu")
			(hatch none 0.5)
			(connect_pads
				(clearance 0)
			)
			(min_thickness 0.25)
			(keepout
				(tracks not_allowed)
				(vias allowed)
				(pads allowed)
				(copperpour not_allowed)
				(footprints allowed)
			)
			(placement
				(enabled no)
				(sheetname "")
			)
			(fill
				(thermal_gap 0.5)
				(thermal_bridge_width 0.5)
				(island_removal_mode 0)
			)
			(polygon
				(pts
					(xy 63.9318 -89.1032) (xy 63.9318 -88.5952) (xy 63.5508 -88.5952) (xy 63.5508 -89.1032)
				)
			)
		)
	)
	(footprint ""
		(layer "B.Cu")
		(at 198.615808 -53.127402 90)
		(property "Reference" "C4E6"
			(at 0 0 90)
			(layer "B.SilkS")
			(hide yes)
			(effects
				(font
					(size 1.27 1.27)
				)
				(justify mirror)
			)
		)
		(property "Value" "*"
			(at -1.1811 -2.8194 90)
			(unlocked yes)
			(layer "B.Fab")
			(hide yes)
			(effects
				(font
					(size 1.27 1.016)
					(thickness 0.1524)
				)
				(justify mirror)
			)
		)
		(property "Device Type" "SC1U10V2KX-4-GP_SMD-BCG6-SC1U1A"
			(at -1.1811 -4.3434 90)
			(unlocked yes)
			(layer "B.Fab")
			(hide yes)
			(effects
				(font
					(size 1.27 1.016)
					(thickness 0.1524)
				)
				(justify mirror)
			)
		)
		(duplicate_pad_numbers_are_jumpers no)
		(fp_rect
			(start 0.4318 0.9525)
			(end -0.4318 -0.9525)
			(stroke
				(width 0)
				(type default)
			)
			(fill no)
			(layer "B.CrtYd")
		)
		(fp_rect
			(start 0.4318 0.9525)
			(end -0.4318 -0.9525)
			(stroke
				(width 0)
				(type default)
			)
			(fill no)
			(layer "B.Fab")
		)
		(pad "1" smd custom
			(at 0 -0.4445 270)
			(size 0.1524 0.1524)
			(layers "B.Cu" "B.Mask" "B.Paste")
			(net "P5V_STBY")
			(options
				(clearance outline)
				(anchor circle)
			)
			(primitives
				(gr_poly
					(pts
						(arc
							(start 0.3048 0.2032)
							(mid 0.275042 0.275042)
							(end 0.2032 0.3048)
						)
						(arc
							(start -0.2032 0.3048)
							(mid -0.275042 0.275042)
							(end -0.3048 0.2032)
						)
						(arc
							(start -0.3048 -0.2032)
							(mid -0.275042 -0.275042)
							(end -0.2032 -0.3048)
						)
						(arc
							(start 0.2032 -0.3048)
							(mid 0.275042 -0.275042)
							(end 0.3048 -0.2032)
						)
					)
					(width 0)
					(fill yes)
				)
			)
		)
		(pad "2" smd custom
			(at 0 0.4445 270)
			(size 0.1524 0.1524)
			(layers "B.Cu" "B.Mask" "B.Paste")
			(net "GND")
			(options
				(clearance outline)
				(anchor circle)
			)
			(primitives
				(gr_poly
					(pts
						(arc
							(start 0.3048 0.2032)
							(mid 0.275042 0.275042)
							(end 0.2032 0.3048)
						)
						(arc
							(start -0.2032 0.3048)
							(mid -0.275042 0.275042)
							(end -0.3048 0.2032)
						)
						(arc
							(start -0.3048 -0.2032)
							(mid -0.275042 -0.275042)
							(end -0.2032 -0.3048)
						)
						(arc
							(start 0.2032 -0.3048)
							(mid 0.275042 -0.275042)
							(end 0.3048 -0.2032)
						)
					)
					(width 0)
					(fill yes)
				)
			)
		)
	)
	(footprint ""
		(layer "B.Cu")
		(at 443.405006 -41.648126 180)
		(property "Reference" "R25W16"
			(at 0 0 0)
			(layer "B.SilkS")
			(hide yes)
			(effects
				(font
					(size 1.27 1.27)
				)
				(justify mirror)
			)
		)
		(property "Value" "*"
			(at -0.064008 -4.108196 180)
			(unlocked yes)
			(layer "B.Fab")
			(hide yes)
			(effects
				(font
					(size 1.27 1.016)
					(thickness 0.1524)
				)
				(justify mirror)
			)
		)
		(property "Device Type" "120R2F-GP_RCL_GP-120R2F-GP,64.A"
			(at -0.064008 -5.632196 180)
			(unlocked yes)
			(layer "B.Fab")
			(hide yes)
			(effects
				(font
					(size 1.27 1.016)
					(thickness 0.1524)
				)
				(justify mirror)
			)
		)
		(duplicate_pad_numbers_are_jumpers no)
		(fp_line
			(start 0.508 -0.9398)
			(end 0.508 0.9398)
			(stroke
				(width 0.1524)
				(type default)
			)
			(layer "B.SilkS")
		)
		(fp_line
			(start -0.508 -0.9398)
			(end 0.508 -0.9398)
			(stroke
				(width 0.1524)
				(type default)
			)
			(layer "B.SilkS")
		)
		(fp_rect
			(start 0.508 0.9398)
			(end -0.508 -0.9398)
			(stroke
				(width 0)
				(type default)
			)
			(fill no)
			(layer "B.CrtYd")
		)
		(fp_rect
			(start 0.508 0.9398)
			(end -0.508 -0.9398)
			(stroke
				(width 0)
				(type default)
			)
			(fill no)
			(layer "B.Fab")
		)
		(pad "1" smd custom
			(at 0 -0.4445)
			(size 0.1397 0.1397)
			(layers "B.Cu" "B.Mask" "B.Paste")
			(net "GND")
			(options
				(clearance outline)
				(anchor circle)
			)
			(primitives
				(gr_poly
					(pts
						(arc
							(start -0.1778 0.2794)
							(mid -0.249642 0.249642)
							(end -0.2794 0.1778)
						)
						(arc
							(start -0.2794 -0.1778)
							(mid -0.249642 -0.249642)
							(end -0.1778 -0.2794)
						)
						(arc
							(start 0.1778 -0.2794)
							(mid 0.249642 -0.249642)
							(end 0.2794 -0.1778)
						)
						(arc
							(start 0.2794 0.1778)
							(mid 0.249642 0.249642)
							(end 0.1778 0.2794)
						)
					)
					(width 0)
					(fill yes)
				)
			)
		)
		(pad "2" smd custom
			(at 0 0.4445)
			(size 0.1397 0.1397)
			(layers "B.Cu" "B.Mask" "B.Paste")
			(net "BMC_M_A4")
			(options
				(clearance outline)
				(anchor circle)
			)
			(primitives
				(gr_poly
					(pts
						(arc
							(start -0.1778 0.2794)
							(mid -0.249642 0.249642)
							(end -0.2794 0.1778)
						)
						(arc
							(start -0.2794 -0.1778)
							(mid -0.249642 -0.249642)
							(end -0.1778 -0.2794)
						)
						(arc
							(start 0.1778 -0.2794)
							(mid 0.249642 -0.249642)
							(end 0.2794 -0.1778)
						)
						(arc
							(start 0.2794 0.1778)
							(mid 0.249642 0.249642)
							(end 0.1778 0.2794)
						)
					)
					(width 0)
					(fill yes)
				)
			)
		)
	)
	(footprint ""
		(layer "B.Cu")
		(at 479.16211 4.716272 180)
		(property "Reference" "R9G1"
			(at 0 0 0)
			(layer "B.SilkS")
			(hide yes)
			(effects
				(font
					(size 1.27 1.27)
				)
				(justify mirror)
			)
		)
		(property "Value" ""
			(at 0 0 0)
			(layer "B.Fab")
			(effects
				(font
					(size 1.27 1.27)
				)
				(justify mirror)
			)
		)
		(duplicate_pad_numbers_are_jumpers no)
		(fp_poly
			(pts
				(xy 0.2794 -0.1016) (xy -0.2794 -0.1016) (xy -0.2794 0.9906) (xy 0.2794 0.9906)
			)
			(stroke
				(width 0)
				(type default)
			)
			(fill no)
			(layer "B.CrtYd")
		)
		(fp_line
			(start 0.2794 0.9906)
			(end -0.2794 0.9906)
			(stroke
				(width 0.1)
				(type default)
			)
			(layer "B.Fab")
		)
		(fp_line
			(start 0.2794 -0.1016)
			(end 0.2794 0.9906)
			(stroke
				(width 0.1)
				(type default)
			)
			(layer "B.Fab")
		)
		(fp_line
			(start -0.2794 0.9906)
			(end -0.2794 -0.1016)
			(stroke
				(width 0.1)
				(type default)
			)
			(layer "B.Fab")
		)
		(fp_line
			(start -0.2794 -0.1016)
			(end 0.2794 -0.1016)
			(stroke
				(width 0.1)
				(type default)
			)
			(layer "B.Fab")
		)
		(pad "1" smd rect
			(at 0 0)
			(size 0.508 0.508)
			(layers "B.Cu" "B.Mask" "B.Paste")
			(net "LED_LAN_1_N")
		)
		(pad "2" smd rect
			(at 0 0.889)
			(size 0.508 0.508)
			(layers "B.Cu" "B.Mask" "B.Paste")
			(net "LED_LAN_1_R_N")
		)
		(zone
			(layer "B.Cu")
			(hatch none 0.5)
			(connect_pads
				(clearance 0)
			)
			(min_thickness 0.25)
			(keepout
				(tracks not_allowed)
				(vias allowed)
				(pads allowed)
				(copperpour not_allowed)
				(footprints allowed)
			)
			(placement
				(enabled no)
				(sheetname "")
			)
			(fill
				(thermal_gap 0.5)
				(thermal_bridge_width 0.5)
				(island_removal_mode 0)
			)
			(polygon
				(pts
					(xy 478.90811 4.081272) (xy 479.41611 4.081272) (xy 479.41611 4.462272) (xy 478.90811 4.462272)
				)
			)
		)
		(zone
			(layer "B.Cu")
			(hatch none 0.5)
			(connect_pads
				(clearance 0)
			)
			(min_thickness 0.25)
			(keepout
				(tracks allowed)
				(vias not_allowed)
				(pads allowed)
				(copperpour not_allowed)
				(footprints allowed)
			)
			(placement
				(enabled no)
				(sheetname "")
			)
			(fill
				(thermal_gap 0.5)
				(thermal_bridge_width 0.5)
				(island_removal_mode 0)
			)
			(polygon
				(pts
					(xy 478.90811 4.462272) (xy 479.41611 4.462272) (xy 479.41611 4.081272) (xy 478.90811 4.081272)
				)
			)
		)
	)
	(footprint ""
		(layer "B.Cu")
		(at 179.39258 -60.99683 180)
		(property "Reference" "C22W20"
			(at 0 0 0)
			(layer "B.SilkS")
			(hide yes)
			(effects
				(font
					(size 1.27 1.27)
				)
				(justify mirror)
			)
		)
		(property "Value" "*"
			(at 0.0762 -6.2357 180)
			(unlocked yes)
			(layer "B.Fab")
			(hide yes)
			(effects
				(font
					(size 1.27 1.016)
					(thickness 0.1524)
				)
				(justify mirror)
			)
		)
		(property "Device Type" "SC22U16V5MX-4-GP_SMD-BCG5-SC22A"
			(at 0.0762 -8.2677 180)
			(unlocked yes)
			(layer "B.Fab")
			(hide yes)
			(effects
				(font
					(size 1.27 1.016)
					(thickness 0.1524)
				)
				(justify mirror)
			)
		)
		(duplicate_pad_numbers_are_jumpers no)
		(fp_line
			(start -0.635 0)
			(end 0.635 0)
			(stroke
				(width 0.508)
				(type default)
			)
			(layer "B.SilkS")
		)
		(fp_rect
			(start 0.9652 1.778)
			(end -0.9652 -1.778)
			(stroke
				(width 0)
				(type default)
			)
			(fill no)
			(layer "B.CrtYd")
		)
		(fp_poly
			(pts
				(xy 0.9652 -1.778) (xy -0.9652 -1.778) (xy -0.9652 1.778) (xy 0.9652 1.778)
			)
			(stroke
				(width 0)
				(type default)
			)
			(fill no)
			(layer "B.Fab")
		)
		(pad "1" smd rect
			(at 0 -0.9652)
			(size 1.397 1.143)
			(layers "B.Cu" "B.Mask" "B.Paste")
			(net "VR_FET_SW_P12V_STBY_PVCCIN_CPU0")
		)
		(pad "2" smd rect
			(at 0 0.9652)
			(size 1.397 1.143)
			(layers "B.Cu" "B.Mask" "B.Paste")
			(net "GND")
		)
	)
	(footprint ""
		(layer "B.Cu")
		(at 94.308168 -3.321812 90)
		(property "Reference" "C5G117"
			(at -1.64973 0.78994 180)
			(unlocked yes)
			(layer "B.SilkS")
			(effects
				(font
					(size 0.7874 0.5842)
					(thickness 0.1524)
				)
				(justify mirror)
			)
		)
		(property "Value" ""
			(at 0 0 90)
			(layer "B.Fab")
			(effects
				(font
					(size 1.27 1.27)
				)
				(justify mirror)
			)
		)
		(duplicate_pad_numbers_are_jumpers no)
		(fp_rect
			(start -0.7239 -0.2159)
			(end 0.7239 1.9939)
			(stroke
				(width 0)
				(type default)
			)
			(fill no)
			(layer "B.CrtYd")
		)
		(fp_line
			(start 0.7239 -0.2159)
			(end 0.7239 1.9939)
			(stroke
				(width 0.1)
				(type default)
			)
			(layer "B.Fab")
		)
		(fp_line
			(start -0.7239 -0.2159)
			(end 0.7239 -0.2159)
			(stroke
				(width 0.1)
				(type default)
			)
			(layer "B.Fab")
		)
		(fp_line
			(start 0.7239 1.9939)
			(end -0.7239 1.9939)
			(stroke
				(width 0.1)
				(type default)
			)
			(layer "B.Fab")
		)
		(fp_line
			(start -0.7239 1.9939)
			(end -0.7239 -0.2159)
			(stroke
				(width 0.1)
				(type default)
			)
			(layer "B.Fab")
		)
		(pad "1" smd rect
			(at 0 0 270)
			(size 1.27 1.016)
			(layers "B.Cu" "B.Mask" "B.Paste")
			(net "PVDDQ_GHJ")
		)
		(pad "2" smd rect
			(at 0 1.778 270)
			(size 1.27 1.016)
			(layers "B.Cu" "B.Mask" "B.Paste")
			(net "GND")
		)
		(zone
			(layer "B.Cu")
			(hatch none 0.5)
			(connect_pads
				(clearance 0)
			)
			(min_thickness 0.25)
			(keepout
				(tracks not_allowed)
				(vias allowed)
				(pads allowed)
				(copperpour not_allowed)
				(footprints allowed)
			)
			(placement
				(enabled no)
				(sheetname "")
			)
			(fill
				(thermal_gap 0.5)
				(thermal_bridge_width 0.5)
				(island_removal_mode 0)
			)
			(polygon
				(pts
					(xy 94.816168 -2.686812) (xy 95.578168 -2.686812) (xy 95.578168 -3.956812) (xy 94.816168 -3.956812)
				)
			)
		)
	)
	(footprint ""
		(layer "B.Cu")
		(at 488.09148 -29.3116)
		(property "Reference" "R1R7"
			(at 0.8382 -0.67818 0)
			(unlocked yes)
			(layer "B.SilkS")
			(effects
				(font
					(size 0.4064 0.254)
					(thickness 0.1524)
				)
				(justify left mirror)
			)
		)
		(property "Value" ""
			(at 0 0 0)
			(layer "B.Fab")
			(effects
				(font
					(size 1.27 1.27)
				)
				(justify mirror)
			)
		)
		(duplicate_pad_numbers_are_jumpers no)
		(fp_poly
			(pts
				(xy 0.2794 -0.1016) (xy -0.2794 -0.1016) (xy -0.2794 0.9906) (xy 0.2794 0.9906)
			)
			(stroke
				(width 0)
				(type default)
			)
			(fill no)
			(layer "B.CrtYd")
		)
		(fp_line
			(start -0.2794 -0.1016)
			(end 0.2794 -0.1016)
			(stroke
				(width 0.1)
				(type default)
			)
			(layer "B.Fab")
		)
		(fp_line
			(start -0.2794 0.9906)
			(end -0.2794 -0.1016)
			(stroke
				(width 0.1)
				(type default)
			)
			(layer "B.Fab")
		)
		(fp_line
			(start 0.2794 -0.1016)
			(end 0.2794 0.9906)
			(stroke
				(width 0.1)
				(type default)
			)
			(layer "B.Fab")
		)
		(fp_line
			(start 0.2794 0.9906)
			(end -0.2794 0.9906)
			(stroke
				(width 0.1)
				(type default)
			)
			(layer "B.Fab")
		)
		(pad "1" smd rect
			(at 0 0 180)
			(size 0.508 0.508)
			(layers "B.Cu" "B.Mask" "B.Paste")
			(net "P3V3_STBY")
		)
		(pad "2" smd rect
			(at 0 0.889 180)
			(size 0.508 0.508)
			(layers "B.Cu" "B.Mask" "B.Paste")
			(net "SPI_NIC_MOSI")
		)
		(zone
			(layer "B.Cu")
			(hatch none 0.5)
			(connect_pads
				(clearance 0)
			)
			(min_thickness 0.25)
			(keepout
				(tracks allowed)
				(vias not_allowed)
				(pads allowed)
				(copperpour not_allowed)
				(footprints allowed)
			)
			(placement
				(enabled no)
				(sheetname "")
			)
			(fill
				(thermal_gap 0.5)
				(thermal_bridge_width 0.5)
				(island_removal_mode 0)
			)
			(polygon
				(pts
					(xy 488.34548 -29.0576) (xy 487.83748 -29.0576) (xy 487.83748 -28.6766) (xy 488.34548 -28.6766)
				)
			)
		)
		(zone
			(layer "B.Cu")
			(hatch none 0.5)
			(connect_pads
				(clearance 0)
			)
			(min_thickness 0.25)
			(keepout
				(tracks not_allowed)
				(vias allowed)
				(pads allowed)
				(copperpour not_allowed)
				(footprints allowed)
			)
			(placement
				(enabled no)
				(sheetname "")
			)
			(fill
				(thermal_gap 0.5)
				(thermal_bridge_width 0.5)
				(island_removal_mode 0)
			)
			(polygon
				(pts
					(xy 488.34548 -28.6766) (xy 487.83748 -28.6766) (xy 487.83748 -29.0576) (xy 488.34548 -29.0576)
				)
			)
		)
	)
)
